FILE_TYPE = MACRO_DRAWING;
SET COLOR_WIRE YELLOW;
SET COLOR_PROP MONO;
SET COLOR_DOT WHITE;
SET COLOR_ARC YELLOW;
SET COLOR_BODY GREEN;
SET COLOR_NOTE MONO;
SET PROP_DISPLAY VALUE;
SET PAGE_NUMBER P246;
FORCEADD OFFPAGE..1
(-7000 2475);
FORCEPROP 2 LAST $XR2 ?
J 0
(-7252 2475);
DISPLAY 0.638298 (-7252 2475);
PAINT MONO (-7252 2475);
FORCEPROP 2 LAST $XR1 ?
J 0
(-7427 2475);
DISPLAY 0.638298 (-7427 2475);
PAINT MONO (-7427 2475);
FORCEPROP 2 LAST $XR0 146 
J 0
(-7352 2475);
DISPLAY 0.638298 (-7352 2475);
PAINT MONO (-7352 2475);
FORCEPROP 1 LAST COMMENT_BODY TRUE
J 0
(-6875 2375);
DISPLAY 0.978723 (-6875 2375);
PAINT PEACH (-6875 2375);
DISPLAY INVISIBLE (-6875 2375);
FORCEPROP 1 LAST OFFPAGE TRUE
J 0
(-6675 2350);
PAINT GREEN (-6675 2350);
DISPLAY INVISIBLE (-6675 2350);
FORCEPROP 2 LAST PATH I1
J 0
(-7250 2525);
DISPLAY 1.021277 (-7250 2525);
PAINT ORANGE (-7250 2525);
DISPLAY INVISIBLE (-7250 2525);
FORCEPROP 2 LAST CDS_LIB mstr_standard
J 0
(-7000 2475);
DISPLAY 1.531915 (-7000 2475);
PAINT ORANGE (-7000 2475);
DISPLAY INVISIBLE (-7000 2475);
FORCEADD RES..2
R 2
(-6275 3150);
FORCEPROP 1 LAST VALUE 4.75K
J 2
(-6320 3225);
DISPLAY 0.617021 (-6320 3225);
PAINT SKYBLUE (-6320 3225);
FORCEPROP 1 LAST MATERIAL CHIP
J 2
(-6315 3175);
DISPLAY 0.617021 (-6315 3175);
PAINT SKYBLUE (-6315 3175);
FORCEPROP 1 LAST TOLERANCE 1%
J 2
(-6320 3125);
DISPLAY 0.617021 (-6320 3125);
PAINT SKYBLUE (-6320 3125);
FORCEPROP 1 LAST WATTAGE 1/16W
J 2
(-6315 3075);
DISPLAY 0.617021 (-6315 3075);
PAINT SKYBLUE (-6315 3075);
FORCEPROP 1 LAST PART_NUMBER G21796-072
J 2
(-6315 3025);
DISPLAY 0.617021 (-6315 3025);
PAINT BLUE (-6315 3025);
FORCEPROP 1 LAST PACK_TYPE 0402
J 2
(-6315 2975);
DISPLAY 0.617021 (-6315 2975);
PAINT SKYBLUE (-6315 2975);
FORCEPROP 1 LAST LOCATION RN8F2
J 2
(-6320 3275);
DISPLAY 0.617021 (-6320 3275);
PAINT AQUA (-6320 3275);
FORCEPROP 1 LAST PATH I10
J 2
(-6325 3325);
DISPLAY 0.978723 (-6325 3325);
PAINT WHITE (-6325 3325);
DISPLAY INVISIBLE (-6325 3325);
FORCEPROP 1 LASTPIN (-6275 3050) $PN 2
J 2
(-6280 3060);
DISPLAY 0.787234 (-6280 3060);
PAINT ORANGE (-6280 3060);
DISPLAY INVISIBLE (-6280 3060);
FORCEPROP 1 LASTPIN (-6275 3250) $PN 1
J 2
(-6280 3212);
DISPLAY 0.787234 (-6280 3212);
PAINT ORANGE (-6280 3212);
DISPLAY INVISIBLE (-6280 3212);
FORCEPROP 2 LAST CDS_LIB mstr_discrete
J 0
(-6275 3150);
PAINT ORANGE (-6275 3150);
DISPLAY INVISIBLE (-6275 3150);
FORCEPROP 2 LAST $SEC 1
J 0
(-6325 3375);
PAINT MONO (-6325 3375);
DISPLAY INVISIBLE (-6325 3375);
FORCEPROP 2 LAST CDS_SEC 1
J 0
(-6325 3375);
PAINT MONO (-6325 3375);
DISPLAY INVISIBLE (-6325 3375);
FORCEPROP 2 LAST BOM_COST SM_MEM
J 0
(-6300 3375);
DISPLAY 1.021277 (-6300 3375);
PAINT ORANGE (-6300 3375);
DISPLAY INVISIBLE (-6300 3375);
FORCEPROP 2 LAST ROOM BMC_BOOT_SPI
J 0
(-6300 3325);
DISPLAY 1.021277 (-6300 3325);
PAINT ORANGE (-6300 3325);
DISPLAY INVISIBLE (-6300 3325);
FORCEPROP 0 LAST CDS_LOCATION RN8F2
J 0
(-6300 3325);
PAINT MONO (-6300 3325);
DISPLAY INVISIBLE (-6300 3325);
FORCEADD RES..2
R 2
(-6000 3175);
FORCEPROP 1 LAST PART_NUMBER G21796-072
J 2
(-6040 3050);
DISPLAY 0.617021 (-6040 3050);
PAINT BLUE (-6040 3050);
FORCEPROP 1 LAST LOCATION RN8F3
J 2
(-6045 3300);
DISPLAY 0.617021 (-6045 3300);
PAINT AQUA (-6045 3300);
FORCEPROP 1 LAST VALUE 4.75K
J 2
(-6045 3250);
DISPLAY 0.617021 (-6045 3250);
PAINT SKYBLUE (-6045 3250);
FORCEPROP 1 LAST MATERIAL CHIP
J 2
(-6040 3200);
DISPLAY 0.617021 (-6040 3200);
PAINT SKYBLUE (-6040 3200);
FORCEPROP 1 LAST TOLERANCE 1%
J 2
(-6045 3150);
DISPLAY 0.617021 (-6045 3150);
PAINT SKYBLUE (-6045 3150);
FORCEPROP 1 LASTPIN (-6000 3075) $PN 2
J 2
(-6005 3085);
DISPLAY 0.617021 (-6005 3085);
PAINT ORANGE (-6005 3085);
FORCEPROP 1 LAST WATTAGE 1/16W
J 2
(-6040 3100);
DISPLAY 0.617021 (-6040 3100);
PAINT SKYBLUE (-6040 3100);
FORCEPROP 1 LASTPIN (-6000 3275) $PN 1
J 2
(-6005 3237);
DISPLAY 0.617021 (-6005 3237);
PAINT ORANGE (-6005 3237);
FORCEPROP 1 LAST PACK_TYPE 0402
J 2
(-6040 3000);
DISPLAY 0.617021 (-6040 3000);
PAINT SKYBLUE (-6040 3000);
FORCEPROP 2 LAST SEC 1
J 0
(-6050 3400);
DISPLAY 0.680851 (-6050 3400);
PAINT MONO (-6050 3400);
DISPLAY INVISIBLE (-6050 3400);
FORCEPROP 2 LAST ROOM BMC_BOOT_SPI
J 0
(-6025 3350);
DISPLAY 1.021277 (-6025 3350);
PAINT ORANGE (-6025 3350);
DISPLAY INVISIBLE (-6025 3350);
FORCEPROP 2 LAST SEC_TYPE 0402
J 0
(-6050 3400);
DISPLAY 1.021277 (-6050 3400);
PAINT ORANGE (-6050 3400);
DISPLAY INVISIBLE (-6050 3400);
FORCEPROP 2 LAST BOM_COST SM_MEM
J 0
(-6025 3400);
DISPLAY 1.021277 (-6025 3400);
PAINT ORANGE (-6025 3400);
DISPLAY INVISIBLE (-6025 3400);
FORCEPROP 2 LAST CDS_LIB mstr_discrete
J 0
(-6000 3175);
PAINT ORANGE (-6000 3175);
DISPLAY INVISIBLE (-6000 3175);
FORCEPROP 0 LAST CDS_SEC 1
J 0
(-6025 3350);
PAINT MONO (-6025 3350);
DISPLAY INVISIBLE (-6025 3350);
FORCEPROP 1 LAST PATH I11
J 2
(-6050 3350);
DISPLAY 0.978723 (-6050 3350);
PAINT WHITE (-6050 3350);
DISPLAY INVISIBLE (-6050 3350);
FORCEPROP 0 LAST CDS_LOCATION RN8F3
J 0
(-6025 3350);
PAINT MONO (-6025 3350);
DISPLAY INVISIBLE (-6025 3350);
FORCEADD RES..2
R 2
(-5425 3150);
FORCEPROP 1 LAST LOCATION RN8F4
J 2
(-5470 3275);
DISPLAY 0.617021 (-5470 3275);
PAINT AQUA (-5470 3275);
FORCEPROP 1 LAST PART_NUMBER G21796-072
J 2
(-5465 3025);
DISPLAY 0.617021 (-5465 3025);
PAINT BLUE (-5465 3025);
FORCEPROP 1 LAST MATERIAL EMPTY
J 2
(-5465 3175);
DISPLAY 0.617021 (-5465 3175);
PAINT RED (-5465 3175);
FORCEPROP 1 LAST VALUE 4.75K
J 2
(-5470 3225);
DISPLAY 0.617021 (-5470 3225);
PAINT SKYBLUE (-5470 3225);
FORCEPROP 1 LAST WATTAGE 1/16W
J 2
(-5465 3075);
DISPLAY 0.617021 (-5465 3075);
PAINT SKYBLUE (-5465 3075);
FORCEPROP 1 LAST TOLERANCE 1%
J 2
(-5470 3125);
DISPLAY 0.617021 (-5470 3125);
PAINT SKYBLUE (-5470 3125);
FORCEPROP 1 LASTPIN (-5425 3050) $PN 2
J 2
(-5430 3060);
DISPLAY 0.617021 (-5430 3060);
PAINT ORANGE (-5430 3060);
FORCEPROP 1 LASTPIN (-5425 3250) $PN 1
J 2
(-5430 3212);
DISPLAY 0.617021 (-5430 3212);
PAINT ORANGE (-5430 3212);
FORCEPROP 1 LAST PACK_TYPE 0402
J 2
(-5465 2975);
DISPLAY 0.617021 (-5465 2975);
PAINT SKYBLUE (-5465 2975);
FORCEPROP 1 LAST PATH I12
J 2
(-5475 3325);
DISPLAY 0.978723 (-5475 3325);
PAINT WHITE (-5475 3325);
DISPLAY INVISIBLE (-5475 3325);
FORCEPROP 0 LAST CDS_SEC 1
J 0
(-5450 3325);
PAINT MONO (-5450 3325);
DISPLAY INVISIBLE (-5450 3325);
FORCEPROP 2 LAST CDS_LIB mstr_discrete
J 0
(-5425 3150);
PAINT ORANGE (-5425 3150);
DISPLAY INVISIBLE (-5425 3150);
FORCEPROP 2 LAST BOM_COST SM_MEM
J 0
(-5450 3375);
DISPLAY 1.021277 (-5450 3375);
PAINT ORANGE (-5450 3375);
DISPLAY INVISIBLE (-5450 3375);
FORCEPROP 2 LAST SEC_TYPE 0402
J 0
(-5475 3375);
DISPLAY 1.021277 (-5475 3375);
PAINT ORANGE (-5475 3375);
DISPLAY INVISIBLE (-5475 3375);
FORCEPROP 2 LAST ROOM BMC_BOOT_SPI
J 0
(-5450 3325);
DISPLAY 1.021277 (-5450 3325);
PAINT ORANGE (-5450 3325);
DISPLAY INVISIBLE (-5450 3325);
FORCEPROP 2 LAST SEC 1
J 0
(-5475 3375);
DISPLAY 0.680851 (-5475 3375);
PAINT MONO (-5475 3375);
DISPLAY INVISIBLE (-5475 3375);
FORCEPROP 0 LAST CDS_LOCATION RN8F4
J 0
(-5450 3325);
PAINT MONO (-5450 3325);
DISPLAY INVISIBLE (-5450 3325);
FORCEADD GND..1
(-3550 2275);
FORCEPROP 3 LASTPIN (-3550 2325) SIG_NAME GND\g
J 0
(-3540 2335);
DISPLAY 0.659574 (-3540 2335);
PAINT MONO (-3540 2335);
DISPLAY INVISIBLE (-3540 2335);
FORCEPROP 1 LAST HDL_POWER GND
J 0
(-3550 2425);
DISPLAY 1.170213 (-3550 2425);
PAINT GREEN (-3550 2425);
DISPLAY INVISIBLE (-3550 2425);
FORCEPROP 1 LAST BODY_TYPE PLUMBING
J 0
(-3595 2232);
DISPLAY 0.340426 (-3595 2232);
PAINT GREEN (-3595 2232);
DISPLAY INVISIBLE (-3595 2232);
FORCEPROP 1 LAST VOLTAGE 0
J 0
(-3550 2275);
PAINT SKYBLUE (-3550 2275);
DISPLAY INVISIBLE (-3550 2275);
FORCEPROP 1 LAST SIZE 1B
J 0
(-3475 2225);
DISPLAY 1.170213 (-3475 2225);
PAINT GREEN (-3475 2225);
DISPLAY INVISIBLE (-3475 2225);
FORCEPROP 2 LAST CDS_LIB mstr_symbols
J 0
(-3550 2275);
PAINT ORANGE (-3550 2275);
DISPLAY INVISIBLE (-3550 2275);
FORCEPROP 1 LAST PATH I13
J 0
(-3475 2275);
DISPLAY 0.872340 (-3475 2275);
PAINT AQUA (-3475 2275);
DISPLAY INVISIBLE (-3475 2275);
FORCEADD GND..1
(-3225 2925);
FORCEPROP 3 LASTPIN (-3225 2975) SIG_NAME GND\g
J 0
(-3215 2985);
DISPLAY 0.659574 (-3215 2985);
PAINT MONO (-3215 2985);
DISPLAY INVISIBLE (-3215 2985);
FORCEPROP 1 LAST HDL_POWER GND
J 0
(-3225 3075);
DISPLAY 0.872340 (-3225 3075);
PAINT GREEN (-3225 3075);
DISPLAY INVISIBLE (-3225 3075);
FORCEPROP 1 LAST BODY_TYPE PLUMBING
J 0
(-3270 2882);
DISPLAY 0.340426 (-3270 2882);
PAINT GREEN (-3270 2882);
DISPLAY INVISIBLE (-3270 2882);
FORCEPROP 1 LAST PATH I14
J 0
(-3150 2925);
DISPLAY 0.872340 (-3150 2925);
PAINT AQUA (-3150 2925);
DISPLAY INVISIBLE (-3150 2925);
FORCEPROP 1 LAST VOLTAGE 0.0V
J 0
(-3270 2882);
DISPLAY 0.340426 (-3270 2882);
PAINT GREEN (-3270 2882);
DISPLAY INVISIBLE (-3270 2882);
FORCEPROP 2 LAST CDS_LIB mstr_symbols
J 0
(-3225 2925);
PAINT ORANGE (-3225 2925);
DISPLAY INVISIBLE (-3225 2925);
FORCEPROP 1 LAST SIZE 1B
J 0
(-3150 2875);
DISPLAY 0.872340 (-3150 2875);
PAINT AQUA (-3150 2875);
DISPLAY INVISIBLE (-3150 2875);
FORCEADD CAP..1
(-3525 3250);
FORCEPROP 1 LAST LOCATION CN8F1
J 0
(-3475 3350);
DISPLAY 0.617021 (-3475 3350);
PAINT AQUA (-3475 3350);
FORCEPROP 1 LAST TOLERANCE 10%
J 0
(-3475 3200);
DISPLAY 0.617021 (-3475 3200);
PAINT SKYBLUE (-3475 3200);
FORCEPROP 1 LAST MATERIAL X6S
J 0
(-3475 3150);
DISPLAY 0.617021 (-3475 3150);
PAINT SKYBLUE (-3475 3150);
FORCEPROP 1 LAST PART_NUMBER D97712-004
J 0
(-3475 3100);
DISPLAY 0.617021 (-3475 3100);
PAINT BLUE (-3475 3100);
FORCEPROP 1 LAST VALUE 1.0UF
J 0
(-3475 3300);
DISPLAY 0.617021 (-3475 3300);
PAINT SKYBLUE (-3475 3300);
FORCEPROP 1 LAST VOLTAGE 6.3V
J 0
(-3475 3250);
DISPLAY 0.617021 (-3475 3250);
PAINT SKYBLUE (-3475 3250);
FORCEPROP 1 LAST PACK_TYPE 0402
J 0
(-3475 3050);
DISPLAY 0.617021 (-3475 3050);
PAINT SKYBLUE (-3475 3050);
FORCEPROP 1 LAST PATH I15
J 0
(-3475 3400);
DISPLAY 0.978723 (-3475 3400);
PAINT WHITE (-3475 3400);
DISPLAY INVISIBLE (-3475 3400);
FORCEPROP 2 LAST CDS_LIB mstr_discrete
J 0
(-3525 3250);
PAINT ORANGE (-3525 3250);
DISPLAY INVISIBLE (-3525 3250);
FORCEPROP 1 LASTPIN (-3525 3150) $PN 2
J 0
(-3515 3130);
DISPLAY 0.787234 (-3515 3130);
PAINT ORANGE (-3515 3130);
DISPLAY INVISIBLE (-3515 3130);
FORCEPROP 1 LASTPIN (-3525 3350) $PN 1
J 0
(-3515 3330);
DISPLAY 0.787234 (-3515 3330);
PAINT ORANGE (-3515 3330);
DISPLAY INVISIBLE (-3515 3330);
FORCEPROP 2 LAST BOM_COST SM_MEM
J 0
(-3475 3450);
DISPLAY 1.021277 (-3475 3450);
PAINT ORANGE (-3475 3450);
DISPLAY INVISIBLE (-3475 3450);
FORCEPROP 2 LAST ROOM BMC_BOOT_SPI
J 0
(-3475 3400);
DISPLAY 1.021277 (-3475 3400);
PAINT ORANGE (-3475 3400);
DISPLAY INVISIBLE (-3475 3400);
FORCEPROP 2 LAST $SEC 1
J 0
(-3475 3450);
PAINT MONO (-3475 3450);
DISPLAY INVISIBLE (-3475 3450);
FORCEPROP 2 LAST CDS_SEC 1
J 0
(-3475 3450);
PAINT MONO (-3475 3450);
DISPLAY INVISIBLE (-3475 3450);
FORCEPROP 0 LAST CDS_LOCATION CN8F1
J 0
(-3475 3400);
PAINT MONO (-3475 3400);
DISPLAY INVISIBLE (-3475 3400);
FORCEADD CAP..1
(-3225 3250);
FORCEPROP 1 LAST LOCATION CN8F2
J 0
(-3175 3350);
DISPLAY 0.617021 (-3175 3350);
PAINT AQUA (-3175 3350);
FORCEPROP 1 LAST PACK_TYPE 0402LF
J 0
(-3175 3050);
DISPLAY 0.617021 (-3175 3050);
PAINT SKYBLUE (-3175 3050);
FORCEPROP 1 LAST PART_NUMBER A36096-045
J 0
(-3175 3100);
DISPLAY 0.617021 (-3175 3100);
PAINT BLUE (-3175 3100);
FORCEPROP 1 LAST VALUE 0.01UF
J 0
(-3175 3300);
DISPLAY 0.617021 (-3175 3300);
PAINT SKYBLUE (-3175 3300);
FORCEPROP 1 LAST VOLTAGE 25V
J 0
(-3175 3250);
DISPLAY 0.617021 (-3175 3250);
PAINT SKYBLUE (-3175 3250);
FORCEPROP 1 LAST TOLERANCE 10%
J 0
(-3175 3200);
DISPLAY 0.617021 (-3175 3200);
PAINT SKYBLUE (-3175 3200);
FORCEPROP 1 LAST MATERIAL X7R
J 0
(-3175 3150);
DISPLAY 0.617021 (-3175 3150);
PAINT SKYBLUE (-3175 3150);
FORCEPROP 1 LAST PATH I16
J 0
(-3175 3400);
DISPLAY 0.978723 (-3175 3400);
PAINT WHITE (-3175 3400);
DISPLAY INVISIBLE (-3175 3400);
FORCEPROP 2 LAST CDS_LIB mstr_discrete
J 0
(-3225 3250);
PAINT ORANGE (-3225 3250);
DISPLAY INVISIBLE (-3225 3250);
FORCEPROP 1 LASTPIN (-3225 3150) $PN 2
J 0
(-3215 3130);
DISPLAY 0.787234 (-3215 3130);
PAINT ORANGE (-3215 3130);
DISPLAY INVISIBLE (-3215 3130);
FORCEPROP 1 LASTPIN (-3225 3350) $PN 1
J 0
(-3215 3330);
DISPLAY 0.787234 (-3215 3330);
PAINT ORANGE (-3215 3330);
DISPLAY INVISIBLE (-3215 3330);
FORCEPROP 2 LAST $SEC 1
J 0
(-3175 3450);
PAINT MONO (-3175 3450);
DISPLAY INVISIBLE (-3175 3450);
FORCEPROP 2 LAST CDS_SEC 1
J 0
(-3175 3450);
PAINT MONO (-3175 3450);
DISPLAY INVISIBLE (-3175 3450);
FORCEPROP 2 LAST BOM_COST SM_MEM
J 0
(-3175 3450);
DISPLAY 1.021277 (-3175 3450);
PAINT ORANGE (-3175 3450);
DISPLAY INVISIBLE (-3175 3450);
FORCEPROP 2 LAST ROOM BMC_BOOT_SPI
J 0
(-3175 3400);
DISPLAY 1.021277 (-3175 3400);
PAINT ORANGE (-3175 3400);
DISPLAY INVISIBLE (-3175 3400);
FORCEPROP 0 LAST CDS_LOCATION CN8F2
J 0
(-3175 3400);
PAINT MONO (-3175 3400);
DISPLAY INVISIBLE (-3175 3400);
FORCEADD W25Q256..1
(-4200 2725);
FORCEPROP 1 LAST LOCATION UN8F2
J 0
(-4550 3150);
DISPLAY 0.617021 (-4550 3150);
PAINT AQUA (-4550 3150);
FORCEPROP 2 LASTPIN (-4750 2775) $PN 9
J 2
(-4760 2785);
DISPLAY 0.617021 (-4760 2785);
PAINT ORANGE (-4760 2785);
FORCEPROP 2 LASTPIN (-4750 2575) $PN 16
J 2
(-4760 2585);
DISPLAY 0.617021 (-4760 2585);
PAINT ORANGE (-4760 2585);
FORCEPROP 2 LASTPIN (-4750 2475) $PN 7
J 2
(-4760 2485);
DISPLAY 0.617021 (-4760 2485);
PAINT ORANGE (-4760 2485);
FORCEPROP 2 LASTPIN (-3650 2925) $PN 4
J 0
(-3640 2935);
DISPLAY 0.617021 (-3640 2935);
PAINT ORANGE (-3640 2935);
FORCEPROP 2 LASTPIN (-3650 2475) $PN 10
J 0
(-3640 2485);
DISPLAY 0.617021 (-3640 2485);
PAINT ORANGE (-3640 2485);
FORCEPROP 2 LASTPIN (-4750 2675) $PN 15
J 2
(-4760 2685);
DISPLAY 0.617021 (-4760 2685);
PAINT ORANGE (-4760 2685);
FORCEPROP 2 LASTPIN (-3650 2625) $PN 14
J 0
(-3640 2635);
DISPLAY 0.617021 (-3640 2635);
PAINT ORANGE (-3640 2635);
FORCEPROP 2 LASTPIN (-3650 2775) $PN 11
J 0
(-3640 2785);
DISPLAY 0.617021 (-3640 2785);
PAINT ORANGE (-3640 2785);
FORCEPROP 2 LASTPIN (-3650 2875) $PN 5
J 0
(-3640 2885);
DISPLAY 0.617021 (-3640 2885);
PAINT ORANGE (-3640 2885);
FORCEPROP 2 LASTPIN (-4750 2425) $PN 3
J 2
(-4760 2435);
DISPLAY 0.617021 (-4760 2435);
PAINT ORANGE (-4760 2435);
FORCEPROP 2 LASTPIN (-4750 2725) $PN 8
J 2
(-4760 2735);
DISPLAY 0.617021 (-4760 2735);
PAINT ORANGE (-4760 2735);
FORCEPROP 2 LASTPIN (-4750 2825) $PN 1
J 2
(-4760 2835);
DISPLAY 0.617021 (-4760 2835);
PAINT ORANGE (-4760 2835);
FORCEPROP 2 LASTPIN (-4750 2925) $PN 2
J 2
(-4760 2935);
DISPLAY 0.617021 (-4760 2935);
PAINT ORANGE (-4760 2935);
FORCEPROP 2 LASTPIN (-3650 2825) $PN 6
J 0
(-3640 2835);
DISPLAY 0.617021 (-3640 2835);
PAINT ORANGE (-3640 2835);
FORCEPROP 2 LASTPIN (-3650 2675) $PN 13
J 0
(-3640 2685);
DISPLAY 0.617021 (-3640 2685);
PAINT ORANGE (-3640 2685);
FORCEPROP 1 LAST MATERIAL IC
J 0
(-4700 3125);
DISPLAY 0.617021 (-4700 3125);
PAINT SKYBLUE (-4700 3125);
FORCEPROP 2 LASTPIN (-3650 2725) $PN 12
J 0
(-3640 2735);
DISPLAY 0.617021 (-3640 2735);
PAINT ORANGE (-3640 2735);
FORCEPROP 1 LAST PART_NUMBER H25002-001
J 0
(-4700 2225);
DISPLAY 0.617021 (-4700 2225);
PAINT BLUE (-4700 2225);
FORCEPROP 1 LAST PATH I17
J 0
(-4200 3125);
PAINT GREEN (-4200 3125);
DISPLAY INVISIBLE (-4200 3125);
FORCEPROP 0 LAST CDS_SEC 1
J 0
(-4550 3200);
PAINT MONO (-4550 3200);
DISPLAY INVISIBLE (-4550 3200);
FORCEPROP 0 LAST CDS_LOCATION UN8F2
J 0
(-4550 3200);
PAINT MONO (-4550 3200);
DISPLAY INVISIBLE (-4550 3200);
FORCEPROP 2 LAST CDS_LIB mstr_memory
J 0
(-4200 2725);
PAINT MONO (-4200 2725);
DISPLAY INVISIBLE (-4200 2725);
FORCEPROP 1 LAST PACK_TYPE XSOI
J 0
(-4700 3225);
PAINT SKYBLUE (-4700 3225);
DISPLAY INVISIBLE (-4700 3225);
FORCEPROP 2 LAST ROOM BMC_BOOT_SPI
J 0
(-4700 3175);
DISPLAY 1.021277 (-4700 3175);
PAINT ORANGE (-4700 3175);
DISPLAY INVISIBLE (-4700 3175);
FORCEPROP 2 LAST SEC_TYPE XSOI
J 0
(-4550 3200);
DISPLAY 1.021277 (-4550 3200);
PAINT ORANGE (-4550 3200);
DISPLAY INVISIBLE (-4550 3200);
FORCEPROP 2 LAST BOM_COST SM_MEM
J 0
(-4700 3225);
DISPLAY 1.021277 (-4700 3225);
PAINT ORANGE (-4700 3225);
DISPLAY INVISIBLE (-4700 3225);
FORCEPROP 2 LAST SEC 1
J 0
(-4550 3200);
DISPLAY 0.680851 (-4550 3200);
PAINT MONO (-4550 3200);
DISPLAY INVISIBLE (-4550 3200);
FORCEADD OFFPAGE..1
(-7000 2575);
FORCEPROP 2 LAST $XR1 151 
J 0
(-7427 2575);
DISPLAY 0.638298 (-7427 2575);
PAINT MONO (-7427 2575);
FORCEPROP 2 LAST $XR2 162 
J 0
(-7252 2575);
DISPLAY 0.638298 (-7252 2575);
PAINT MONO (-7252 2575);
FORCEPROP 2 LAST $XR0 146 
J 0
(-7352 2575);
DISPLAY 0.638298 (-7352 2575);
PAINT MONO (-7352 2575);
FORCEPROP 1 LAST COMMENT_BODY TRUE
J 0
(-6875 2475);
DISPLAY 0.978723 (-6875 2475);
PAINT PEACH (-6875 2475);
DISPLAY INVISIBLE (-6875 2475);
FORCEPROP 1 LAST OFFPAGE TRUE
J 0
(-6675 2450);
PAINT GREEN (-6675 2450);
DISPLAY INVISIBLE (-6675 2450);
FORCEPROP 2 LAST PATH I2
J 0
(-7250 2625);
DISPLAY 1.021277 (-7250 2625);
PAINT ORANGE (-7250 2625);
DISPLAY INVISIBLE (-7250 2625);
FORCEPROP 2 LAST CDS_LIB mstr_standard
J 0
(-7000 2575);
DISPLAY 1.531915 (-7000 2575);
PAINT ORANGE (-7000 2575);
DISPLAY INVISIBLE (-7000 2575);
FORCEADD OFFPAGE..1
(-7000 2675);
FORCEPROP 2 LAST $XR2 162 
J 0
(-7252 2675);
DISPLAY 0.638298 (-7252 2675);
PAINT MONO (-7252 2675);
FORCEPROP 2 LAST $XR0 146 
J 0
(-7352 2675);
DISPLAY 0.638298 (-7352 2675);
PAINT MONO (-7352 2675);
FORCEPROP 2 LAST $XR1 151 
J 0
(-7427 2675);
DISPLAY 0.638298 (-7427 2675);
PAINT MONO (-7427 2675);
FORCEPROP 1 LAST COMMENT_BODY TRUE
J 0
(-6875 2575);
DISPLAY 0.978723 (-6875 2575);
PAINT PEACH (-6875 2575);
DISPLAY INVISIBLE (-6875 2575);
FORCEPROP 1 LAST OFFPAGE TRUE
J 0
(-6675 2550);
PAINT GREEN (-6675 2550);
DISPLAY INVISIBLE (-6675 2550);
FORCEPROP 2 LAST PATH I3
J 0
(-7250 2725);
DISPLAY 1.021277 (-7250 2725);
PAINT ORANGE (-7250 2725);
DISPLAY INVISIBLE (-7250 2725);
FORCEPROP 2 LAST CDS_LIB mstr_standard
J 0
(-7000 2675);
DISPLAY 1.531915 (-7000 2675);
PAINT ORANGE (-7000 2675);
DISPLAY INVISIBLE (-7000 2675);
FORCEADD OFFPAGE..5
(-7000 2725);
FORCEPROP 2 LAST $XR2 151 
J 0
(-7355 2725);
DISPLAY 0.638298 (-7355 2725);
PAINT MONO (-7355 2725);
FORCEPROP 2 LAST $XR0 162 
J 0
(-7255 2725);
DISPLAY 0.638298 (-7255 2725);
PAINT MONO (-7255 2725);
FORCEPROP 2 LAST $XR1 146 
J 0
(-7430 2725);
DISPLAY 0.638298 (-7430 2725);
PAINT MONO (-7430 2725);
FORCEPROP 1 LAST COMMENT_BODY TRUE
J 0
(-6900 2650);
DISPLAY 1.170213 (-6900 2650);
PAINT GREEN (-6900 2650);
DISPLAY INVISIBLE (-6900 2650);
FORCEPROP 1 LAST OFFPAGE TRUE
J 0
(-6675 2600);
PAINT GREEN (-6675 2600);
DISPLAY INVISIBLE (-6675 2600);
FORCEPROP 2 LAST PATH I4
J 0
(-7250 2775);
DISPLAY 1.021277 (-7250 2775);
PAINT ORANGE (-7250 2775);
DISPLAY INVISIBLE (-7250 2775);
FORCEPROP 2 LAST CDS_LIB mstr_standard
J 1
(-7000 2725);
PAINT ORANGE (-7000 2725);
DISPLAY INVISIBLE (-7000 2725);
FORCEADD RES..2
R 2
(-6600 3175);
FORCEPROP 1 LAST LOCATION RN8F1
J 2
(-6645 3300);
DISPLAY 0.617021 (-6645 3300);
PAINT AQUA (-6645 3300);
FORCEPROP 1 LAST PART_NUMBER G21796-072
J 2
(-6640 3050);
DISPLAY 0.617021 (-6640 3050);
PAINT BLUE (-6640 3050);
FORCEPROP 1 LAST WATTAGE 1/16W
J 2
(-6640 3100);
DISPLAY 0.617021 (-6640 3100);
PAINT SKYBLUE (-6640 3100);
FORCEPROP 1 LAST TOLERANCE 1%
J 2
(-6645 3150);
DISPLAY 0.617021 (-6645 3150);
PAINT SKYBLUE (-6645 3150);
FORCEPROP 1 LAST MATERIAL CHIP
J 2
(-6640 3200);
DISPLAY 0.617021 (-6640 3200);
PAINT SKYBLUE (-6640 3200);
FORCEPROP 1 LAST VALUE 4.75K
J 2
(-6645 3250);
DISPLAY 0.617021 (-6645 3250);
PAINT SKYBLUE (-6645 3250);
FORCEPROP 1 LAST PACK_TYPE 0402
J 2
(-6640 3000);
DISPLAY 0.617021 (-6640 3000);
PAINT SKYBLUE (-6640 3000);
FORCEPROP 2 LAST CDS_SEC 1
J 0
(-6650 3400);
PAINT MONO (-6650 3400);
DISPLAY INVISIBLE (-6650 3400);
FORCEPROP 2 LAST $SEC 1
J 0
(-6650 3400);
PAINT MONO (-6650 3400);
DISPLAY INVISIBLE (-6650 3400);
FORCEPROP 2 LAST ROOM BMC_BOOT_SPI
J 0
(-6625 3350);
DISPLAY 1.021277 (-6625 3350);
PAINT ORANGE (-6625 3350);
DISPLAY INVISIBLE (-6625 3350);
FORCEPROP 2 LAST BOM_COST SM_MEM
J 0
(-6625 3400);
DISPLAY 1.021277 (-6625 3400);
PAINT ORANGE (-6625 3400);
DISPLAY INVISIBLE (-6625 3400);
FORCEPROP 1 LASTPIN (-6600 3275) $PN 1
J 2
(-6605 3237);
DISPLAY 0.787234 (-6605 3237);
PAINT ORANGE (-6605 3237);
DISPLAY INVISIBLE (-6605 3237);
FORCEPROP 2 LAST CDS_LIB mstr_discrete
J 0
(-6600 3175);
PAINT ORANGE (-6600 3175);
DISPLAY INVISIBLE (-6600 3175);
FORCEPROP 1 LASTPIN (-6600 3075) $PN 2
J 2
(-6605 3085);
DISPLAY 0.787234 (-6605 3085);
PAINT ORANGE (-6605 3085);
DISPLAY INVISIBLE (-6605 3085);
FORCEPROP 1 LAST PATH I5
J 2
(-6650 3350);
DISPLAY 0.978723 (-6650 3350);
PAINT WHITE (-6650 3350);
DISPLAY INVISIBLE (-6650 3350);
FORCEPROP 0 LAST CDS_LOCATION RN8F1
J 0
(-6625 3350);
PAINT MONO (-6625 3350);
DISPLAY INVISIBLE (-6625 3350);
FORCEADD P3V3_STBY..1
(-6000 3575);
FORCEPROP 3 LASTPIN (-6000 3525) SIG_NAME P3V3_STBY\g
J 0
(-5990 3535);
DISPLAY 0.659574 (-5990 3535);
PAINT MONO (-5990 3535);
DISPLAY INVISIBLE (-5990 3535);
FORCEPROP 1 LAST HDL_POWER P3V3_STBY
J 0
(-6300 3450);
DISPLAY 0.872340 (-6300 3450);
PAINT ORANGE (-6300 3450);
DISPLAY INVISIBLE (-6300 3450);
FORCEPROP 1 LAST BODY_TYPE PLUMBING
J 0
(-6045 3532);
DISPLAY 0.340426 (-6045 3532);
PAINT GREEN (-6045 3532);
DISPLAY INVISIBLE (-6045 3532);
FORCEPROP 1 LAST PATH I6
J 0
(-5955 3577);
DISPLAY 0.340426 (-5955 3577);
PAINT GREEN (-5955 3577);
DISPLAY INVISIBLE (-5955 3577);
FORCEPROP 1 LAST VOLTAGE 3.3V
J 0
(-6045 3532);
DISPLAY 0.340426 (-6045 3532);
PAINT GREEN (-6045 3532);
DISPLAY INVISIBLE (-6045 3532);
FORCEPROP 2 LAST CDS_LIB mstr_symbols
J 0
(-6000 3575);
PAINT ORANGE (-6000 3575);
DISPLAY INVISIBLE (-6000 3575);
FORCEPROP 1 LAST SIZE 1B
J 0
(-5955 3597);
DISPLAY 0.340426 (-5955 3597);
PAINT GREEN (-5955 3597);
DISPLAY INVISIBLE (-5955 3597);
FORCEADD GND..1
(-6275 1900);
FORCEPROP 3 LASTPIN (-6275 1950) SIG_NAME GND\g
J 0
(-6265 1960);
DISPLAY 0.659574 (-6265 1960);
PAINT MONO (-6265 1960);
DISPLAY INVISIBLE (-6265 1960);
FORCEPROP 1 LAST HDL_POWER GND
J 0
(-6275 2050);
DISPLAY 0.872340 (-6275 2050);
PAINT GREEN (-6275 2050);
DISPLAY INVISIBLE (-6275 2050);
FORCEPROP 1 LAST BODY_TYPE PLUMBING
J 0
(-6320 1857);
DISPLAY 0.340426 (-6320 1857);
PAINT GREEN (-6320 1857);
DISPLAY INVISIBLE (-6320 1857);
FORCEPROP 1 LAST PATH I7
J 0
(-6200 1900);
DISPLAY 0.872340 (-6200 1900);
PAINT AQUA (-6200 1900);
DISPLAY INVISIBLE (-6200 1900);
FORCEPROP 1 LAST VOLTAGE 0.0V
J 0
(-6320 1857);
DISPLAY 0.340426 (-6320 1857);
PAINT GREEN (-6320 1857);
DISPLAY INVISIBLE (-6320 1857);
FORCEPROP 2 LAST CDS_LIB mstr_symbols
J 0
(-6275 1900);
PAINT ORANGE (-6275 1900);
DISPLAY INVISIBLE (-6275 1900);
FORCEPROP 1 LAST SIZE 1B
J 0
(-6200 1850);
DISPLAY 0.872340 (-6200 1850);
PAINT AQUA (-6200 1850);
DISPLAY INVISIBLE (-6200 1850);
FORCEADD RES..2
(-6275 2225);
FORCEPROP 1 LAST PACK_TYPE 0402
J 0
(-6235 2050);
DISPLAY 0.617021 (-6235 2050);
PAINT SKYBLUE (-6235 2050);
FORCEPROP 1 LAST LOCATION RN8F6
J 0
(-6230 2350);
DISPLAY 0.617021 (-6230 2350);
PAINT AQUA (-6230 2350);
FORCEPROP 1 LAST MATERIAL EMPTY
J 0
(-6235 2150);
DISPLAY 0.617021 (-6235 2150);
PAINT RED (-6235 2150);
FORCEPROP 1 LAST PART_NUMBER G21796-026
J 0
(-6235 2100);
DISPLAY 0.617021 (-6235 2100);
PAINT BLUE (-6235 2100);
FORCEPROP 1 LAST WATTAGE 1/16W
J 0
(-6235 2200);
DISPLAY 0.617021 (-6235 2200);
PAINT SKYBLUE (-6235 2200);
FORCEPROP 1 LAST TOLERANCE 1%
J 0
(-6230 2250);
DISPLAY 0.617021 (-6230 2250);
PAINT SKYBLUE (-6230 2250);
FORCEPROP 1 LAST VALUE 1.00K
J 0
(-6230 2300);
DISPLAY 0.617021 (-6230 2300);
PAINT SKYBLUE (-6230 2300);
FORCEPROP 1 LAST PATH I8
J 0
(-6225 2400);
DISPLAY 0.978723 (-6225 2400);
PAINT WHITE (-6225 2400);
DISPLAY INVISIBLE (-6225 2400);
FORCEPROP 1 LASTPIN (-6275 2125) $PN 2
J 0
(-6270 2135);
DISPLAY 0.787234 (-6270 2135);
PAINT ORANGE (-6270 2135);
DISPLAY INVISIBLE (-6270 2135);
FORCEPROP 2 LAST CDS_LIB mstr_discrete
J 0
(-6275 2225);
PAINT ORANGE (-6275 2225);
DISPLAY INVISIBLE (-6275 2225);
FORCEPROP 1 LASTPIN (-6275 2325) $PN 1
J 0
(-6270 2287);
DISPLAY 0.787234 (-6270 2287);
PAINT ORANGE (-6270 2287);
DISPLAY INVISIBLE (-6270 2287);
FORCEPROP 2 LAST BOM_COST SM_MEM
J 0
(-6225 2450);
DISPLAY 1.021277 (-6225 2450);
PAINT ORANGE (-6225 2450);
DISPLAY INVISIBLE (-6225 2450);
FORCEPROP 2 LAST ROOM BMC_BOOT_SPI
J 0
(-6225 2400);
DISPLAY 1.021277 (-6225 2400);
PAINT ORANGE (-6225 2400);
DISPLAY INVISIBLE (-6225 2400);
FORCEPROP 2 LAST $SEC 1
J 0
(-6225 2450);
PAINT MONO (-6225 2450);
DISPLAY INVISIBLE (-6225 2450);
FORCEPROP 2 LAST CDS_SEC 1
J 0
(-6225 2450);
PAINT MONO (-6225 2450);
DISPLAY INVISIBLE (-6225 2450);
FORCEPROP 0 LAST CDS_LOCATION RN8F6
J 0
(-6225 2400);
PAINT MONO (-6225 2400);
DISPLAY INVISIBLE (-6225 2400);
FORCEADD RES..1
(-5850 2725);
FORCEPROP 1 LAST VALUE 33.2
J 2
(-5625 2732);
DISPLAY 0.617021 (-5625 2732);
PAINT SKYBLUE (-5625 2732);
FORCEPROP 1 LASTPIN (-5950 2725) $PN 1
J 0
(-5938 2737);
DISPLAY 0.617021 (-5938 2737);
PAINT MONO (-5938 2737);
FORCEPROP 1 LAST LOCATION RN8F5
J 0
(-6157 2732);
DISPLAY 0.617021 (-6157 2732);
PAINT AQUA (-6157 2732);
FORCEPROP 1 LASTPIN (-5750 2725) $PN 2
J 0
(-5788 2737);
DISPLAY 0.617021 (-5788 2737);
PAINT MONO (-5788 2737);
FORCEPROP 1 LAST PATH I9
J 0
(-5900 2875);
DISPLAY 0.978723 (-5900 2875);
PAINT WHITE (-5900 2875);
DISPLAY INVISIBLE (-5900 2875);
FORCEPROP 0 LAST CDS_SEC 1
J 0
(-5625 2775);
PAINT MONO (-5625 2775);
DISPLAY INVISIBLE (-5625 2775);
FORCEPROP 1 LAST WATTAGE 1/16W
J 2
(-5875 2575);
PAINT SKYBLUE (-5875 2575);
DISPLAY INVISIBLE (-5875 2575);
FORCEPROP 1 LAST TOLERANCE 1%
J 0
(-5775 2575);
PAINT SKYBLUE (-5775 2575);
DISPLAY INVISIBLE (-5775 2575);
FORCEPROP 2 LAST CDS_LIB mstr_discrete
J 1
(-5850 2725);
PAINT ORANGE (-5850 2725);
DISPLAY INVISIBLE (-5850 2725);
FORCEPROP 2 LAST ROOM BMC_BOOT_SPI
J 0
(-5625 2775);
DISPLAY 1.021277 (-5625 2775);
PAINT ORANGE (-5625 2775);
DISPLAY INVISIBLE (-5625 2775);
FORCEPROP 1 LAST MATERIAL CHIP
J 0
(-5650 2725);
PAINT SKYBLUE (-5650 2725);
DISPLAY INVISIBLE (-5650 2725);
FORCEPROP 1 LAST PACK_TYPE 0402
J 0
(-5600 2575);
PAINT SKYBLUE (-5600 2575);
DISPLAY INVISIBLE (-5600 2575);
FORCEPROP 2 LAST BOM_COST SM_MEM
J 0
(-5625 2825);
DISPLAY 1.021277 (-5625 2825);
PAINT ORANGE (-5625 2825);
DISPLAY INVISIBLE (-5625 2825);
FORCEPROP 1 LAST PART_NUMBER G21796-074
J 0
(-5900 2825);
PAINT BLUE (-5900 2825);
DISPLAY INVISIBLE (-5900 2825);
FORCEPROP 2 LAST SEC_TYPE 0402
J 0
(-5900 2950);
DISPLAY 1.021277 (-5900 2950);
PAINT ORANGE (-5900 2950);
DISPLAY INVISIBLE (-5900 2950);
FORCEPROP 2 LAST SEC 1
J 0
(-5900 2950);
DISPLAY 0.680851 (-5900 2950);
PAINT MONO (-5900 2950);
DISPLAY INVISIBLE (-5900 2950);
FORCEPROP 0 LAST CDS_LOCATION RN8F5
J 0
(-5625 2775);
PAINT MONO (-5625 2775);
DISPLAY INVISIBLE (-5625 2775);
FORCEADD BOM_NOTE..1
(-4450 1700);
FORCEPROP 0 LAST L1 SOCKET IS D91187-001
J 0
(-4600 1600);
DISPLAY 0.617021 (-4600 1600);
PAINT WHITE (-4600 1600);
FORCEPROP 1 LAST COMMENT_BODY TRUE
J 0
(-4425 1800);
DISPLAY 1.319149 (-4425 1800);
PAINT WHITE (-4425 1800);
DISPLAY INVISIBLE (-4425 1800);
FORCEPROP 2 LAST CDS_LIB mstr_symbols
J 0
(-4450 1700);
PAINT WHITE (-4450 1700);
DISPLAY INVISIBLE (-4450 1700);
FORCEADD DNS..2
(-5420 3145);
PAINT RED (-5420 3145);
FORCEPROP 1 LAST COMMENT_BODY TRUE
R 1
J 0
(-5345 2920);
DISPLAY 0.872340 (-5345 2920);
PAINT GREEN (-5345 2920);
DISPLAY INVISIBLE (-5345 2920);
FORCEPROP 2 LAST CDS_LIB mstr_misc
J 0
(-5420 3145);
PAINT ORANGE (-5420 3145);
DISPLAY INVISIBLE (-5420 3145);
FORCEADD DNS..2
(-6270 2220);
PAINT RED (-6270 2220);
FORCEPROP 1 LAST COMMENT_BODY TRUE
R 1
J 0
(-6195 1995);
DISPLAY 0.872340 (-6195 1995);
PAINT GREEN (-6195 1995);
DISPLAY INVISIBLE (-6195 1995);
FORCEPROP 2 LAST CDS_LIB mstr_misc
J 0
(-6270 2220);
PAINT ORANGE (-6270 2220);
DISPLAY INVISIBLE (-6270 2220);
FORCEADD CAD_NOTE..1
(-2800 3275);
FORCEPROP 0 LAST L1 PLACE CAPS NEAR VCC PIN ON W25Q256 COMPONENT
J 0
(-2950 3150);
DISPLAY 1.021277 (-2950 3150);
PAINT ORANGE (-2950 3150);
FORCEPROP 1 LAST COMMENT_BODY TRUE
J 0
(-2775 3375);
DISPLAY 0.978723 (-2775 3375);
PAINT ORANGE (-2775 3375);
DISPLAY INVISIBLE (-2775 3375);
FORCEPROP 2 LAST CDS_LIB mstr_symbols
J 0
(-2800 3275);
PAINT ORANGE (-2800 3275);
DISPLAY INVISIBLE (-2800 3275);
FORCEADD INTEL_CORP_BPAGE..1
(0 0);
FORCEPROP 1 LAST CDS_CON_LAST_MODIFIED Tue Dec 01 11:52:33 2015
J 0
(-1425 325);
PAINT ORANGE (-1425 325);
DISPLAY INVISIBLE (-1425 325);
FORCEPROP 1 LAST CUSTOM_TXT_CDS <CURRENT_DESIGN_SHEET> OF <TOTAL_DESIGN_SHEETS>
J 0
(-500 25);
PAINT GREEN (-500 25);
FORCEPROP 1 LAST CUSTOM_TXT_CDS <CON_LAST_MODIFIED>
J 0
(-1925 350);
PAINT GREEN (-1925 350);
FORCEPROP 2 LAST CUSTOM_TXT_CDS <XR_PAGE_TITLE>
J 0
(-7890 5250);
DISPLAY 0.638298 (-7890 5250);
PAINT PINK (-7890 5250);
DISPLAY INVISIBLE (-7890 5250);
FORCEPROP 1 LAST SCH_TITLE 2ND FLASH FOR TPM
J 0
(-7950 50);
DISPLAY 2.468085 (-7950 50);
PAINT ORANGE (-7950 50);
FORCEPROP 1 LAST SCH_DEPT UNKNOWN
J 1
(-4450 100);
DISPLAY 1.255319 (-4450 100);
PAINT ORANGE (-4450 100);
FORCEPROP 1 LAST SCH_ADDRESS2 P.O. BOX 58119
J 0
(-3975 75);
DISPLAY 0.872340 (-3975 75);
PAINT GREEN (-3975 75);
FORCEPROP 1 LAST SCH_REV 0.1
J 0
(-250 150);
DISPLAY 1.170213 (-250 150);
PAINT GREEN (-250 150);
FORCEPROP 1 LAST SCH_ADDRESS3 Santa Clara, CA 95052-8119
J 0
(-3975 25);
DISPLAY 0.872340 (-3975 25);
PAINT GREEN (-3975 25);
FORCEPROP 1 LAST SCH_NUMBER 000000-000
J 0
(-1300 150);
DISPLAY 1.702128 (-1300 150);
PAINT GREEN (-1300 150);
FORCEPROP 1 LAST SCH_ADDRESS1 2200 Mission College Blvd.
J 0
(-3975 125);
DISPLAY 0.872340 (-3975 125);
PAINT GREEN (-3975 125);
FORCEPROP 1 LAST COMMENT_BODY TRUE
J 0
(12 12);
DISPLAY 0.468085 (12 12);
PAINT GREEN (12 12);
DISPLAY INVISIBLE (12 12);
FORCEPROP 2 LAST PAGE_BORDER TRUE
J 0
(-7890 5250);
DISPLAY 0.638298 (-7890 5250);
PAINT PINK (-7890 5250);
DISPLAY INVISIBLE (-7890 5250);
FORCEPROP 2 LAST CDS_LIB mstr_symbols
J 0
(0 0);
PAINT MONO (0 0);
DISPLAY INVISIBLE (0 0);
FORCEPROP 2 LAST CDS_XR_PAGE_TITLE CR-246 : @BASEBOARD_FAB2_LIB.BASEBOARD_FAB2(SCH_1):PAGE246
J 0
(-7890 5250);
DISPLAY 0.638298 (-7890 5250);
PAINT PINK (-7890 5250);
DISPLAY INVISIBLE (-7890 5250);
FORCEADD CAD_NOTE..1
(-4450 2000);
FORCEPROP 0 LAST L1 THIS PART WILL BE IN SOCKET, PLEASE
J 0
(-4600 1900);
DISPLAY 0.617021 (-4600 1900);
PAINT WHITE (-4600 1900);
FORCEPROP 0 LAST L2 USE ALT SYMBOL ASSOCIATED WITH PART FOOTPRINT
J 0
(-4600 1850);
DISPLAY 0.617021 (-4600 1850);
PAINT WHITE (-4600 1850);
FORCEPROP 1 LAST COMMENT_BODY TRUE
J 0
(-4425 2100);
DISPLAY 1.319149 (-4425 2100);
PAINT WHITE (-4425 2100);
DISPLAY INVISIBLE (-4425 2100);
FORCEPROP 2 LAST CDS_LIB mstr_symbols
J 0
(-4450 2000);
PAINT WHITE (-4450 2000);
DISPLAY INVISIBLE (-4450 2000);
WIRE 16 -1 (-3550 2325)(-3550 2475);
WIRE 16 -1 (-3550 2475)(-3650 2475);
WIRE 16 -1 (-3525 3050)(-3525 3150);
WIRE 16 -1 (-3225 3050)(-3525 3050);
WIRE 16 -1 (-3225 3150)(-3225 3050);
WIRE 16 -1 (-3225 2975)(-3225 3050);
WIRE 16 -1 (-3225 3350)(-3225 3400);
WIRE 16 -1 (-3225 3400)(-3525 3400);
WIRE 16 -1 (-3525 3400)(-3525 3350);
WIRE 16 -1 (-3525 3400)(-5175 3400);
WIRE 16 -1 (-5175 3400)(-5175 2925);
WIRE 16 -1 (-5175 3400)(-5425 3400);
WIRE 16 -1 (-5425 3250)(-5425 3400);
WIRE 16 -1 (-5425 3400)(-6000 3400);
WIRE 16 -1 (-5175 2925)(-4750 2925);
WIRE 16 -1 (-6275 3400)(-6000 3400);
WIRE 16 -1 (-6000 3275)(-6000 3400);
WIRE 16 -1 (-6000 3525)(-6000 3400);
WIRE 16 -1 (-6600 3400)(-6275 3400);
WIRE 16 -1 (-6275 3250)(-6275 3400);
WIRE 16 -1 (-6600 3275)(-6600 3400);
WIRE 16 -1 (-6275 1950)(-6275 2125);
WIRE 16 -1 (-6275 3050)(-6275 2775);
WIRE 16 -1 (-4750 2775)(-6275 2775);
FORCEPROP 2 LAST SIG_NAME PU_TPM_SPI_BMC_WP_N
J 0
(-5960 2785);
DISPLAY 0.617021 (-5960 2785);
PAINT ORANGE (-5960 2785);
FORCEPROP 2 LASTPROP $XRERR UNIQUE?
J 0
(-6200 2785);
DISPLAY 0.638298 (-6200 2785);
PAINT MONO (-6200 2785);
DISPLAY INVISIBLE (-6200 2785);
WIRE 16 -1 (-6275 2325)(-6275 2775);
WIRE 16 -1 (-6950 2725)(-5950 2725);
FORCEPROP 2 LAST SIG_NAME SPI_BMC_BT_DI
J 0
(-6950 2735);
DISPLAY 0.617021 (-6950 2735);
PAINT ORANGE (-6950 2735);
WIRE 16 -1 (-4750 2675)(-6950 2675);
FORCEPROP 2 LAST SIG_NAME SPI_BMC_BT_DO
J 0
(-6950 2685);
DISPLAY 0.617021 (-6950 2685);
PAINT ORANGE (-6950 2685);
WIRE 16 -1 (-6950 2575)(-4750 2575);
FORCEPROP 2 LAST SIG_NAME SPI_BMC_BT_CLK
J 0
(-6950 2585);
DISPLAY 0.617021 (-6950 2585);
PAINT ORANGE (-6950 2585);
WIRE 16 -1 (-4750 2475)(-6600 2475);
FORCEPROP 2 LAST SIG_NAME SPI_BMC_CS0_N
J 2
(-6625 2485);
DISPLAY 0.680851 (-6625 2485);
PAINT ORANGE (-6625 2485);
WIRE 16 -1 (-6600 3075)(-6600 2475);
WIRE 16 -1 (-6600 2475)(-6950 2475);
WIRE 3 2175 (-7775 4550)(-550 4550);
WIRE 3 2175 (-7775 4550)(-7775 800);
WIRE 3 2175 (-550 4550)(-550 800);
WIRE 3 2175 (-7775 800)(-550 800);
WIRE 17 2175 (-4825 2175)(-3725 2175);
WIRE 17 2175 (-4825 3225)(-4825 2175);
WIRE 17 2175 (-3725 3225)(-3725 2175);
WIRE 17 2175 (-4825 3225)(-3725 3225);
WIRE 16 -1 (-3275 2925)(-3650 2925);
FORCEPROP 2 LAST SIG_NAME TP_TPM_SPI_6
J 0
(-3585 2935);
DISPLAY 0.617021 (-3585 2935);
PAINT ORANGE (-3585 2935);
FORCEPROP 2 LASTPROP $XRERR UNIQUE?
J 0
(-3245 2925);
DISPLAY 0.638298 (-3245 2925);
PAINT MONO (-3245 2925);
DISPLAY INVISIBLE (-3245 2925);
WIRE 16 -1 (-3275 2875)(-3650 2875);
FORCEPROP 2 LAST SIG_NAME TP_TPM_SPI_5
J 0
(-3585 2885);
DISPLAY 0.617021 (-3585 2885);
PAINT ORANGE (-3585 2885);
FORCEPROP 2 LASTPROP $XRERR UNIQUE?
J 0
(-3245 2875);
DISPLAY 0.638298 (-3245 2875);
PAINT MONO (-3245 2875);
DISPLAY INVISIBLE (-3245 2875);
WIRE 16 -1 (-3275 2775)(-3650 2775);
FORCEPROP 2 LAST SIG_NAME TP_TPM_SPI_3
J 0
(-3585 2785);
DISPLAY 0.617021 (-3585 2785);
PAINT ORANGE (-3585 2785);
FORCEPROP 2 LASTPROP $XRERR UNIQUE?
J 0
(-3245 2775);
DISPLAY 0.638298 (-3245 2775);
PAINT MONO (-3245 2775);
DISPLAY INVISIBLE (-3245 2775);
WIRE 16 -1 (-3275 2725)(-3650 2725);
FORCEPROP 2 LAST SIG_NAME TP_TPM_SPI_2
J 0
(-3585 2735);
DISPLAY 0.617021 (-3585 2735);
PAINT ORANGE (-3585 2735);
FORCEPROP 2 LASTPROP $XRERR UNIQUE?
J 0
(-3245 2725);
DISPLAY 0.638298 (-3245 2725);
PAINT MONO (-3245 2725);
DISPLAY INVISIBLE (-3245 2725);
WIRE 16 -1 (-3275 2825)(-3650 2825);
FORCEPROP 2 LAST SIG_NAME TP_TPM_SPI_4
J 0
(-3585 2835);
DISPLAY 0.617021 (-3585 2835);
PAINT ORANGE (-3585 2835);
FORCEPROP 2 LASTPROP $XRERR UNIQUE?
J 0
(-3245 2825);
DISPLAY 0.638298 (-3245 2825);
PAINT MONO (-3245 2825);
DISPLAY INVISIBLE (-3245 2825);
WIRE 16 -1 (-3275 2675)(-3650 2675);
FORCEPROP 2 LAST SIG_NAME TP_TPM_SPI_1
J 0
(-3585 2685);
DISPLAY 0.617021 (-3585 2685);
PAINT ORANGE (-3585 2685);
FORCEPROP 2 LASTPROP $XRERR UNIQUE?
J 0
(-3245 2675);
DISPLAY 0.638298 (-3245 2675);
PAINT MONO (-3245 2675);
DISPLAY INVISIBLE (-3245 2675);
WIRE 16 -1 (-3275 2625)(-3650 2625);
FORCEPROP 2 LAST SIG_NAME TP_TPM_SPI_0
J 0
(-3585 2635);
DISPLAY 0.617021 (-3585 2635);
PAINT ORANGE (-3585 2635);
FORCEPROP 2 LASTPROP $XRERR UNIQUE?
J 0
(-3245 2625);
DISPLAY 0.638298 (-3245 2625);
PAINT MONO (-3245 2625);
DISPLAY INVISIBLE (-3245 2625);
WIRE 16 -1 (-4750 2725)(-5750 2725);
FORCEPROP 2 LAST SIG_NAME SPI_TPM_BMC_DI_R_
J 2
(-5025 2735);
DISPLAY 0.617021 (-5025 2735);
PAINT ORANGE (-5025 2735);
FORCEPROP 2 LASTPROP $XRERR UNIQUE?
J 0
(-5265 2735);
DISPLAY 0.638298 (-5265 2735);
PAINT MONO (-5265 2735);
DISPLAY INVISIBLE (-5265 2735);
WIRE 16 -1 (-6000 2825)(-4750 2825);
FORCEPROP 2 LAST SIG_NAME PU_TPM_SPI_BMC_HOLD_N
J 0
(-5935 2835);
DISPLAY 0.617021 (-5935 2835);
PAINT ORANGE (-5935 2835);
FORCEPROP 2 LASTPROP $XRERR UNIQUE?
J 0
(-6175 2835);
DISPLAY 0.638298 (-6175 2835);
PAINT MONO (-6175 2835);
DISPLAY INVISIBLE (-6175 2835);
WIRE 16 -1 (-6000 3075)(-6000 2825);
WIRE 16 -1 (-5425 3050)(-5425 2425);
FORCEPROP 2 LAST SIG_NAME PU_TPM_SPI_FLASH_RESET_2_N
J 0
(-5385 2435);
DISPLAY 0.617021 (-5385 2435);
PAINT ORANGE (-5385 2435);
FORCEPROP 2 LASTPROP $XRERR UNIQUE?
J 0
(-5625 2435);
DISPLAY 0.638298 (-5625 2435);
PAINT MONO (-5625 2435);
DISPLAY INVISIBLE (-5625 2435);
WIRE 16 -1 (-5425 2425)(-4750 2425);
DOT 1 (-6275 2775);
DOT 1 (-6600 2475);
DOT 1 (-6275 3400);
DOT 1 (-3225 3050);
DOT 1 (-5175 3400);
DOT 1 (-3525 3400);
DOT 1 (-5425 3400);
DOT 1 (-6000 3400);
FORCENOTE
NEED 256M SIZE?
(-4625 2100) 0;
DISPLAY LEFT (-4625 2100);
DISPLAY 1.021277 (-4625 2100);
PAINT RED (-4625 2100);
FORCENOTE
TP FAB1 ADD TPM FLASH
(-4950 1100) 0;
DISPLAY LEFT (-4950 1100);
DISPLAY 1.702128 (-4950 1100);
PAINT RED (-4950 1100);
QUIT
